(kicad_pcb
	(version 20260206)
	(generator "pcbnew")
	(generator_version "10.0")
	(general
		(thickness 1.6)
		(legacy_teardrops no)
	)
	(paper "A4")
	(title_block
		(title "03242023_DA0F0TMBIJ0_F0T_Motherboard_J_brd_V01_OCP.brd")
		(comment 1 "Grand Teton / footprint 3039 of 6105 (U2), pads 957-1062 of 4677")
	)
	(layers
		(0 "F.Cu" signal "TOP")
		(4 "In1.Cu" signal "GND")
		(6 "In2.Cu" signal "IN1")
		(8 "In3.Cu" signal "GND1")
		(10 "In4.Cu" signal "IN2")
		(12 "In5.Cu" signal "GND2")
		(14 "In6.Cu" signal "IN3")
		(16 "In7.Cu" signal "GND3")
		(18 "In8.Cu" signal "VCC")
		(20 "In9.Cu" signal "VCC1")
		(22 "In10.Cu" signal "GND4")
		(24 "In11.Cu" signal "IN4")
		(26 "In12.Cu" signal "GND5")
		(28 "In13.Cu" signal "IN5")
		(30 "In14.Cu" signal "GND6")
		(32 "In15.Cu" signal "IN6")
		(34 "In16.Cu" signal "GND7")
		(2 "B.Cu" signal "BOTTOM")
		(9 "F.Adhes" user "F.Adhesive")
		(11 "B.Adhes" user "B.Adhesive")
		(13 "F.Paste" user "Package Geometry/Pastemask Top")
		(15 "B.Paste" user "Package Geometry/Pastemask Bottom")
		(5 "F.SilkS" user "Ref Des/Silkscreen Top")
		(7 "B.SilkS" user "Ref Des/Silkscreen Bottom")
		(1 "F.Mask" user "Board Geometry/Soldermask Top")
		(3 "B.Mask" user "Board Geometry/Soldermask Bottom")
		(17 "Dwgs.User" user "User.Drawings")
		(19 "Cmts.User" user "User.Comments")
		(21 "Eco1.User" user "User.Eco1")
		(23 "Eco2.User" user "User.Eco2")
		(25 "Edge.Cuts" user "Board Geometry/Outline")
		(27 "Margin" user)
		(31 "F.CrtYd" user "Package Geometry/Place Bound Top")
		(29 "B.CrtYd" user "Package Geometry/Place Bound Bottom")
		(35 "F.Fab" user "Ref Des/Assembly Top")
		(33 "B.Fab" user "Ref Des/Assembly Bottom")
	)
	(footprint ""
		(layer "F.Cu")
		(at 359.870248 -251.76988 90)
		(property "Reference" "U2"
			(at -74.416158 -44.488608 0)
			(unlocked yes)
			(layer "F.SilkS")
			(effects
				(font
					(size 1.6002 1.1938)
					(thickness 0.1524)
				)
				(justify left)
			)
		)
		(property "Value" ""
			(at 0 0 90)
			(layer "F.Fab")
			(effects
				(font
					(size 1.27 1.27)
				)
			)
		)
		(duplicate_pad_numbers_are_jumpers no)
		(pad "BA78" smd circle
			(at 26.844498 -8.168132 270)
			(size 0.4318 0.4318)
			(layers "F.Cu" "F.Mask" "F.Paste")
			(net "UPI_CPU0_CPU1_P2P2_DP<13>")
		)
		(pad "BA80" smd circle
			(at 28.472384 -8.168132 270)
			(size 0.4318 0.4318)
			(layers "F.Cu" "F.Mask" "F.Paste")
			(net "UPI_CPU0_CPU1_P2P2_DN<6>")
		)
		(pad "BA82" smd circle
			(at 30.100016 -8.168132 270)
			(size 0.4318 0.4318)
			(layers "F.Cu" "F.Mask" "F.Paste")
			(net "UPI_CPU0_CPU1_P2P2_DP<5>")
		)
		(pad "BA84" smd circle
			(at 31.727902 -8.168132 270)
			(size 0.4318 0.4318)
			(layers "F.Cu" "F.Mask" "F.Paste")
			(net "GND")
		)
		(pad "BA86" smd circle
			(at 33.355534 -8.168132 270)
			(size 0.4318 0.4318)
			(layers "F.Cu" "F.Mask" "F.Paste")
			(net "P5E_CPU0_PE4_TX_DN<15>")
		)
		(pad "BA88" smd circle
			(at 34.98342 -8.168132 270)
			(size 0.4318 0.4318)
			(layers "F.Cu" "F.Mask" "F.Paste")
			(net "GND")
		)
		(pad "BA90" smd circle
			(at 36.611306 -8.168132 270)
			(size 0.4318 0.4318)
			(layers "F.Cu" "F.Mask" "F.Paste")
			(net "P5E_CPU0_PE4_RX_DP<15>")
		)
		(pad "BB2" smd circle
			(at -36.611306 -7.808468 270)
			(size 0.4318 0.4318)
			(layers "F.Cu" "F.Mask" "F.Paste")
			(net "UPI_CPU0_CPU1_P0P1_DN<16>")
		)
		(pad "BB4" smd circle
			(at -34.98342 -7.808468 270)
			(size 0.4318 0.4318)
			(layers "F.Cu" "F.Mask" "F.Paste")
			(net "GND")
		)
		(pad "BB6" smd circle
			(at -33.355534 -7.808468 270)
			(size 0.4318 0.4318)
			(layers "F.Cu" "F.Mask" "F.Paste")
			(net "UPI_CPU1_CPU0_P1P0_DP<16>")
		)
		(pad "BB8" smd circle
			(at -31.727902 -7.808468 270)
			(size 0.4318 0.4318)
			(layers "F.Cu" "F.Mask" "F.Paste")
			(net "GND")
		)
		(pad "BB10" smd circle
			(at -30.100016 -7.808468 270)
			(size 0.4318 0.4318)
			(layers "F.Cu" "F.Mask" "F.Paste")
			(net "GND")
		)
		(pad "BB12" smd circle
			(at -28.472384 -7.808468 270)
			(size 0.4318 0.4318)
			(layers "F.Cu" "F.Mask" "F.Paste")
			(net "GND")
		)
		(pad "BB14" smd circle
			(at -26.844498 -7.808468 270)
			(size 0.4318 0.4318)
			(layers "F.Cu" "F.Mask" "F.Paste")
			(net "P5E_CPU0_PE0_TX_DN<15>")
		)
		(pad "BB16" smd circle
			(at -25.216612 -7.808468 270)
			(size 0.4318 0.4318)
			(layers "F.Cu" "F.Mask" "F.Paste")
			(net "GND")
		)
		(pad "BB18" smd circle
			(at -23.58898 -7.808468 270)
			(size 0.4318 0.4318)
			(layers "F.Cu" "F.Mask" "F.Paste")
			(net "DMI_CPU0_PCH_RX_C_DN<0>")
		)
		(pad "BB20" smd circle
			(at -21.961094 -7.808468 270)
			(size 0.4318 0.4318)
			(layers "F.Cu" "F.Mask" "F.Paste")
			(net "GND")
		)
		(pad "BB22" smd circle
			(at -20.333462 -7.808468 270)
			(size 0.4318 0.4318)
			(layers "F.Cu" "F.Mask" "F.Paste")
			(net "GND")
		)
		(pad "BB24" smd circle
			(at -18.705576 -7.808468 270)
			(size 0.4318 0.4318)
			(layers "F.Cu" "F.Mask" "F.Paste")
			(net "GND")
		)
		(pad "BB26" smd circle
			(at -17.07769 -7.808468 270)
			(size 0.4318 0.4318)
			(layers "F.Cu" "F.Mask" "F.Paste")
			(net "GND")
		)
		(pad "BB61" smd circle
			(at 13.008356 -7.698486 270)
			(size 0.4318 0.4318)
			(layers "F.Cu" "F.Mask" "F.Paste")
			(net "TP_SPI_S3M_CPU0_CS0_LVC1_R_N")
		)
		(pad "BB63" smd circle
			(at 14.635988 -7.698486 270)
			(size 0.4318 0.4318)
			(layers "F.Cu" "F.Mask" "F.Paste")
			(net "GND")
		)
		(pad "BB65" smd circle
			(at 16.263874 -7.698486 270)
			(size 0.4318 0.4318)
			(layers "F.Cu" "F.Mask" "F.Paste")
			(net "PU_CPU0_UPI2_AC_COUPLING")
		)
		(pad "BB67" smd circle
			(at 17.89176 -7.698486 270)
			(size 0.4318 0.4318)
			(layers "F.Cu" "F.Mask" "F.Paste")
			(net "TP_SPI_IBL_CPU0_TPM_OE_N")
		)
		(pad "BB69" smd circle
			(at 19.519392 -7.698486 270)
			(size 0.4318 0.4318)
			(layers "F.Cu" "F.Mask" "F.Paste")
			(net "GND")
		)
		(pad "BB71" smd circle
			(at 21.147278 -7.698486 270)
			(size 0.4318 0.4318)
			(layers "F.Cu" "F.Mask" "F.Paste")
			(net "GND")
		)
		(pad "BB73" smd circle
			(at 22.77491 -7.698486 270)
			(size 0.4318 0.4318)
			(layers "F.Cu" "F.Mask" "F.Paste")
			(net "UPI_CPU1_CPU0_P2P2_DN<11>")
		)
		(pad "BB75" smd circle
			(at 24.402796 -7.698486 270)
			(size 0.4318 0.4318)
			(layers "F.Cu" "F.Mask" "F.Paste")
			(net "UPI_CPU1_CPU0_P2P2_DP<8>")
		)
		(pad "BB77" smd circle
			(at 26.030682 -7.698486 270)
			(size 0.4318 0.4318)
			(layers "F.Cu" "F.Mask" "F.Paste")
			(net "GND")
		)
		(pad "BB79" smd circle
			(at 27.658314 -7.698486 270)
			(size 0.4318 0.4318)
			(layers "F.Cu" "F.Mask" "F.Paste")
			(net "GND")
		)
		(pad "BB81" smd circle
			(at 29.2862 -7.698486 270)
			(size 0.4318 0.4318)
			(layers "F.Cu" "F.Mask" "F.Paste")
			(net "UPI_CPU0_CPU1_P2P2_DP<6>")
		)
		(pad "BB83" smd circle
			(at 30.914086 -7.698486 270)
			(size 0.4318 0.4318)
			(layers "F.Cu" "F.Mask" "F.Paste")
			(net "GND")
		)
		(pad "BB85" smd circle
			(at 32.541718 -7.698486 270)
			(size 0.4318 0.4318)
			(layers "F.Cu" "F.Mask" "F.Paste")
			(net "P5E_CPU0_PE4_TX_DP<15>")
		)
		(pad "BB87" smd circle
			(at 34.169604 -7.698486 270)
			(size 0.4318 0.4318)
			(layers "F.Cu" "F.Mask" "F.Paste")
			(net "GND")
		)
		(pad "BB89" smd circle
			(at 35.797236 -7.698486 270)
			(size 0.4318 0.4318)
			(layers "F.Cu" "F.Mask" "F.Paste")
			(net "P5E_CPU0_PE4_RX_DN<15>")
		)
		(pad "BB91" smd oval
			(at 37.425122 -7.698486)
			(size 0.381 0.4826)
			(drill
				(offset 0 -0.0508)
			)
			(layers "F.Cu" "F.Mask" "F.Paste")
			(net "GND")
		)
		(pad "BC1" smd oval
			(at -37.425122 -7.338314 180)
			(size 0.381 0.4826)
			(drill
				(offset 0 -0.0508)
			)
			(layers "F.Cu" "F.Mask" "F.Paste")
			(net "GND")
		)
		(pad "BC3" smd circle
			(at -35.797236 -7.338314 270)
			(size 0.4318 0.4318)
			(layers "F.Cu" "F.Mask" "F.Paste")
			(net "UPI_CPU0_CPU1_P0P1_DP<17>")
		)
		(pad "BC5" smd circle
			(at -34.169604 -7.338314 270)
			(size 0.4318 0.4318)
			(layers "F.Cu" "F.Mask" "F.Paste")
			(net "GND")
		)
		(pad "BC7" smd circle
			(at -32.541718 -7.338314 270)
			(size 0.4318 0.4318)
			(layers "F.Cu" "F.Mask" "F.Paste")
			(net "UPI_CPU1_CPU0_P1P0_DN<16>")
		)
		(pad "BC9" smd circle
			(at -30.914086 -7.338314 270)
			(size 0.4318 0.4318)
			(layers "F.Cu" "F.Mask" "F.Paste")
			(net "GND")
		)
		(pad "BC11" smd circle
			(at -29.2862 -7.338314 270)
			(size 0.4318 0.4318)
			(layers "F.Cu" "F.Mask" "F.Paste")
			(net "P5E_CPU0_PE1_RX_DN<15>")
		)
		(pad "BC13" smd circle
			(at -27.658314 -7.338314 270)
			(size 0.4318 0.4318)
			(layers "F.Cu" "F.Mask" "F.Paste")
			(net "GND")
		)
		(pad "BC15" smd circle
			(at -26.030682 -7.338314 270)
			(size 0.4318 0.4318)
			(layers "F.Cu" "F.Mask" "F.Paste")
			(net "P5E_CPU0_PE0_TX_DP<15>")
		)
		(pad "BC17" smd circle
			(at -24.402796 -7.338314 270)
			(size 0.4318 0.4318)
			(layers "F.Cu" "F.Mask" "F.Paste")
			(net "GND")
		)
		(pad "BC19" smd circle
			(at -22.77491 -7.338314 270)
			(size 0.4318 0.4318)
			(layers "F.Cu" "F.Mask" "F.Paste")
			(net "DMI_CPU0_PCH_RX_C_DP<0>")
		)
		(pad "BC21" smd circle
			(at -21.147278 -7.338314 270)
			(size 0.4318 0.4318)
			(layers "F.Cu" "F.Mask" "F.Paste")
			(net "P3V3_AUX")
		)
		(pad "BC23" smd circle
			(at -19.519392 -7.338314 270)
			(size 0.4318 0.4318)
			(layers "F.Cu" "F.Mask" "F.Paste")
			(net "TP_CPU0_IFST_DONE_LVC1_R")
		)
		(pad "BC25" smd circle
			(at -17.89176 -7.338314 270)
			(size 0.4318 0.4318)
			(layers "F.Cu" "F.Mask" "F.Paste")
			(net "TP_I3C_MNG2_BMC_SW_SDA")
		)
		(pad "BC60" smd circle
			(at 12.19454 -7.228332 270)
			(size 0.4318 0.4318)
			(layers "F.Cu" "F.Mask" "F.Paste")
			(net "PVCCINFAON_CPU0")
		)
		(pad "BC62" smd circle
			(at 13.822426 -7.228332 270)
			(size 0.4318 0.4318)
			(layers "F.Cu" "F.Mask" "F.Paste")
			(net "GND")
		)
		(pad "BC64" smd circle
			(at 15.450058 -7.228332 270)
			(size 0.4318 0.4318)
			(layers "F.Cu" "F.Mask" "F.Paste")
			(net "TP_SPI_S3M_CPU0_CLK_LVC1_R")
		)
		(pad "BC66" smd circle
			(at 17.07769 -7.228332 270)
			(size 0.4318 0.4318)
			(layers "F.Cu" "F.Mask" "F.Paste")
			(net "GND")
		)
		(pad "BC68" smd circle
			(at 18.705576 -7.228332 270)
			(size 0.4318 0.4318)
			(layers "F.Cu" "F.Mask" "F.Paste")
			(net "TP_TRC_CPU0_PTI<21>")
		)
		(pad "BC70" smd circle
			(at 20.333462 -7.228332 270)
			(size 0.4318 0.4318)
			(layers "F.Cu" "F.Mask" "F.Paste")
			(net "TP_TRC_CPU0_PTI<16>")
		)
		(pad "BC72" smd circle
			(at 21.961094 -7.228332 270)
			(size 0.4318 0.4318)
			(layers "F.Cu" "F.Mask" "F.Paste")
			(net "GND")
		)
		(pad "BC74" smd circle
			(at 23.58898 -7.228332 270)
			(size 0.4318 0.4318)
			(layers "F.Cu" "F.Mask" "F.Paste")
			(net "UPI_CPU1_CPU0_P2P2_DN<0>")
		)
		(pad "BC76" smd circle
			(at 25.216612 -7.228332 270)
			(size 0.4318 0.4318)
			(layers "F.Cu" "F.Mask" "F.Paste")
			(net "GND")
		)
		(pad "BC78" smd circle
			(at 26.844498 -7.228332 270)
			(size 0.4318 0.4318)
			(layers "F.Cu" "F.Mask" "F.Paste")
			(net "GND")
		)
		(pad "BC80" smd circle
			(at 28.472384 -7.228332 270)
			(size 0.4318 0.4318)
			(layers "F.Cu" "F.Mask" "F.Paste")
			(net "UPI_CPU0_CPU1_P2P2_DP<3>")
		)
		(pad "BC82" smd circle
			(at 30.100016 -7.228332 270)
			(size 0.4318 0.4318)
			(layers "F.Cu" "F.Mask" "F.Paste")
			(net "UPI_CPU0_CPU1_P2P2_DN<5>")
		)
		(pad "BC84" smd circle
			(at 31.727902 -7.228332 270)
			(size 0.4318 0.4318)
			(layers "F.Cu" "F.Mask" "F.Paste")
			(net "GND")
		)
		(pad "BC86" smd circle
			(at 33.355534 -7.228332 270)
			(size 0.4318 0.4318)
			(layers "F.Cu" "F.Mask" "F.Paste")
			(net "GND")
		)
		(pad "BC88" smd circle
			(at 34.98342 -7.228332 270)
			(size 0.4318 0.4318)
			(layers "F.Cu" "F.Mask" "F.Paste")
			(net "GND")
		)
		(pad "BC90" smd circle
			(at 36.611306 -7.228332 270)
			(size 0.4318 0.4318)
			(layers "F.Cu" "F.Mask" "F.Paste")
			(net "VSENSE_PVCCIN_CPU0_DN")
		)
		(pad "BD2" smd circle
			(at -36.611306 -6.868668 270)
			(size 0.4318 0.4318)
			(layers "F.Cu" "F.Mask" "F.Paste")
			(net "UPI_CPU0_CPU1_P0P1_DN<17>")
		)
		(pad "BD4" smd circle
			(at -34.98342 -6.868668 270)
			(size 0.4318 0.4318)
			(layers "F.Cu" "F.Mask" "F.Paste")
			(net "GND")
		)
		(pad "BD6" smd circle
			(at -33.355534 -6.868668 270)
			(size 0.4318 0.4318)
			(layers "F.Cu" "F.Mask" "F.Paste")
			(net "UPI_CPU1_CPU0_P1P0_DN<17>")
		)
		(pad "BD8" smd circle
			(at -31.727902 -6.868668 270)
			(size 0.4318 0.4318)
			(layers "F.Cu" "F.Mask" "F.Paste")
			(net "GND")
		)
		(pad "BD10" smd circle
			(at -30.100016 -6.868668 270)
			(size 0.4318 0.4318)
			(layers "F.Cu" "F.Mask" "F.Paste")
			(net "P5E_CPU0_PE1_RX_DP<15>")
		)
		(pad "BD12" smd circle
			(at -28.472384 -6.868668 270)
			(size 0.4318 0.4318)
			(layers "F.Cu" "F.Mask" "F.Paste")
			(net "GND")
		)
		(pad "BD14" smd circle
			(at -26.844498 -6.868668 270)
			(size 0.4318 0.4318)
			(layers "F.Cu" "F.Mask" "F.Paste")
			(net "P5E_CPU0_PE1_TX_DP<15>")
		)
		(pad "BD16" smd circle
			(at -25.216612 -6.868668 270)
			(size 0.4318 0.4318)
			(layers "F.Cu" "F.Mask" "F.Paste")
			(net "GND")
		)
		(pad "BD18" smd circle
			(at -23.58898 -6.868668 270)
			(size 0.4318 0.4318)
			(layers "F.Cu" "F.Mask" "F.Paste")
			(net "DMI_CPU0_PCH_RX_C_DN<1>")
		)
		(pad "BD20" smd circle
			(at -21.961094 -6.868668 270)
			(size 0.4318 0.4318)
			(layers "F.Cu" "F.Mask" "F.Paste")
			(net "GND")
		)
		(pad "BD22" smd circle
			(at -20.333462 -6.868668 270)
			(size 0.4318 0.4318)
			(layers "F.Cu" "F.Mask" "F.Paste")
			(net "H_CPU0_ERR2_LVC1_R_N")
		)
		(pad "BD24" smd circle
			(at -18.705576 -6.868668 270)
			(size 0.4318 0.4318)
			(layers "F.Cu" "F.Mask" "F.Paste")
			(net "H_PMAX_TRIGGER_IO_CPU0")
		)
		(pad "BD26" smd circle
			(at -17.07769 -6.868668 270)
			(size 0.4318 0.4318)
			(layers "F.Cu" "F.Mask" "F.Paste")
			(net "SVID_DIO0_CPU0")
		)
		(pad "BD61" smd circle
			(at 13.008356 -6.758686 270)
			(size 0.4318 0.4318)
			(layers "F.Cu" "F.Mask" "F.Paste")
			(net "TP_SPI_S3M_CPU0_IO3_LVC1_R")
		)
		(pad "BD63" smd circle
			(at 14.635988 -6.758686 270)
			(size 0.4318 0.4318)
			(layers "F.Cu" "F.Mask" "F.Paste")
			(net "TP_ESPI_IBL_CPU0_ALERT1_N")
		)
		(pad "BD65" smd circle
			(at 16.263874 -6.758686 270)
			(size 0.4318 0.4318)
			(layers "F.Cu" "F.Mask" "F.Paste")
			(net "TP_SPI_S3M_CPU0_IO2_LVC1_R")
		)
		(pad "BD67" smd circle
			(at 17.89176 -6.758686 270)
			(size 0.4318 0.4318)
			(layers "F.Cu" "F.Mask" "F.Paste")
			(net "TP_TRC_CPU0_PTI<23>")
		)
		(pad "BD69" smd circle
			(at 19.519392 -6.758686 270)
			(size 0.4318 0.4318)
			(layers "F.Cu" "F.Mask" "F.Paste")
			(net "TP_TRC_CPU0_PTI<18>")
		)
		(pad "BD71" smd circle
			(at 21.147278 -6.758686 270)
			(size 0.4318 0.4318)
			(layers "F.Cu" "F.Mask" "F.Paste")
			(net "NC_CPU0_MDFI_DIE01_NS1")
		)
		(pad "BD73" smd circle
			(at 22.77491 -6.758686 270)
			(size 0.4318 0.4318)
			(layers "F.Cu" "F.Mask" "F.Paste")
			(net "UPI_CPU1_CPU0_P2P2_DP<0>")
		)
		(pad "BD75" smd circle
			(at 24.402796 -6.758686 270)
			(size 0.4318 0.4318)
			(layers "F.Cu" "F.Mask" "F.Paste")
			(net "UPI_CPU1_CPU0_P2P2_DN<8>")
		)
		(pad "BD77" smd circle
			(at 26.030682 -6.758686 270)
			(size 0.4318 0.4318)
			(layers "F.Cu" "F.Mask" "F.Paste")
			(net "TP_CPU0_SPARE13")
		)
		(pad "BD79" smd circle
			(at 27.658314 -6.758686 270)
			(size 0.4318 0.4318)
			(layers "F.Cu" "F.Mask" "F.Paste")
			(net "UPI_CPU0_CPU1_P2P2_DN<3>")
		)
		(pad "BD81" smd circle
			(at 29.2862 -6.758686 270)
			(size 0.4318 0.4318)
			(layers "F.Cu" "F.Mask" "F.Paste")
			(net "GND")
		)
		(pad "BD83" smd circle
			(at 30.914086 -6.758686 270)
			(size 0.4318 0.4318)
			(layers "F.Cu" "F.Mask" "F.Paste")
			(net "UPI_CPU0_CPU1_P2P2_DP<4>")
		)
		(pad "BD85" smd circle
			(at 32.541718 -6.758686 270)
			(size 0.4318 0.4318)
			(layers "F.Cu" "F.Mask" "F.Paste")
			(net "GND")
		)
		(pad "BD87" smd circle
			(at 34.169604 -6.758686 270)
			(size 0.4318 0.4318)
			(layers "F.Cu" "F.Mask" "F.Paste")
			(net "VSENSE_PVCCIN_CPU0_DP")
		)
		(pad "BD89" smd circle
			(at 35.797236 -6.758686 270)
			(size 0.4318 0.4318)
			(layers "F.Cu" "F.Mask" "F.Paste")
			(net "GND")
		)
		(pad "BD91" smd oval
			(at 37.425122 -6.758686)
			(size 0.381 0.4826)
			(drill
				(offset 0 -0.0508)
			)
			(layers "F.Cu" "F.Mask" "F.Paste")
			(net "PVCCIN_CPU0")
		)
		(pad "BE1" smd oval
			(at -37.425122 -6.398514 180)
			(size 0.381 0.4826)
			(drill
				(offset 0 -0.0508)
			)
			(layers "F.Cu" "F.Mask" "F.Paste")
			(net "UPI_CPU0_CPU1_P0P1_DP<18>")
		)
		(pad "BE3" smd circle
			(at -35.797236 -6.398514 270)
			(size 0.4318 0.4318)
			(layers "F.Cu" "F.Mask" "F.Paste")
			(net "PVCCD_HV_CPU0")
		)
		(pad "BE5" smd circle
			(at -34.169604 -6.398514 270)
			(size 0.4318 0.4318)
			(layers "F.Cu" "F.Mask" "F.Paste")
			(net "UPI_CPU1_CPU0_P1P0_DP<17>")
		)
		(pad "BE7" smd circle
			(at -32.541718 -6.398514 270)
			(size 0.4318 0.4318)
			(layers "F.Cu" "F.Mask" "F.Paste")
			(net "PVCCD_HV_CPU0")
		)
		(pad "BE9" smd circle
			(at -30.914086 -6.398514 270)
			(size 0.4318 0.4318)
			(layers "F.Cu" "F.Mask" "F.Paste")
			(net "P5E_CPU0_PE1_RX_DP<14>")
		)
		(pad "BE11" smd circle
			(at -29.2862 -6.398514 270)
			(size 0.4318 0.4318)
			(layers "F.Cu" "F.Mask" "F.Paste")
			(net "PVCCD_HV_CPU0")
		)
		(pad "BE13" smd circle
			(at -27.658314 -6.398514 270)
			(size 0.4318 0.4318)
			(layers "F.Cu" "F.Mask" "F.Paste")
			(net "P5E_CPU0_PE1_TX_DN<15>")
		)
		(pad "BE15" smd circle
			(at -26.030682 -6.398514 270)
			(size 0.4318 0.4318)
			(layers "F.Cu" "F.Mask" "F.Paste")
			(net "PVCCINFAON_CPU0")
		)
		(pad "BE17" smd circle
			(at -24.402796 -6.398514 270)
			(size 0.4318 0.4318)
			(layers "F.Cu" "F.Mask" "F.Paste")
			(net "DMI_CPU0_PCH_RX_C_DP<1>")
		)
		(pad "BE19" smd circle
			(at -22.77491 -6.398514 270)
			(size 0.4318 0.4318)
			(layers "F.Cu" "F.Mask" "F.Paste")
			(net "PVNN_MAIN_CPU0")
		)
		(pad "BE21" smd circle
			(at -21.147278 -6.398514 270)
			(size 0.4318 0.4318)
			(layers "F.Cu" "F.Mask" "F.Paste")
			(net "TP_CPU0_DIE_HVM_EN_LVC1")
		)
		(pad "BE23" smd circle
			(at -19.519392 -6.398514 270)
			(size 0.4318 0.4318)
			(layers "F.Cu" "F.Mask" "F.Paste")
			(net "TP_CPU0_IFST_KOT_LVC1_R")
		)
	)
)
